# S9S_MB_2U (Grand Teton) — schematic netlist excerpt (pin names and nets, part order shuffled) for the footprints in the layout excerpt that follows; sources: Cadence DE-HDL packaged netlist, KiCad conversion of 03242023_DA0F0TMBIJ0_F0T_Motherboard_J_brd_V01_OCP.brd

R3397  Q_RES  33.2 1% CHIP  pkg 0402LF  page 150 : A = GPU_NVS_PWR_BRAKE_N_R ; B = GPU_NVS_PWR_BRAKE_N_BUF
PC441  Q_CAP  2.2UF 10V 10% X6S  pkg C0402  page 293 : A = PVCCINFAON_CPU1_VDD2 ; B = GND

(kicad_pcb
	(version 20260206)
	(generator "pcbnew")
	(generator_version "10.0")
	(general
		(thickness 1.6)
		(legacy_teardrops no)
	)
	(paper "A4")
	(title_block
		(title "03242023_DA0F0TMBIJ0_F0T_Motherboard_J_brd_V01_OCP.brd")
		(comment 1 "Grand Teton / footprints 1306-1307 of 6105")
	)
	(layers
		(0 "F.Cu" signal "TOP")
		(4 "In1.Cu" signal "GND")
		(6 "In2.Cu" signal "IN1")
		(8 "In3.Cu" signal "GND1")
		(10 "In4.Cu" signal "IN2")
		(12 "In5.Cu" signal "GND2")
		(14 "In6.Cu" signal "IN3")
		(16 "In7.Cu" signal "GND3")
		(18 "In8.Cu" signal "VCC")
		(20 "In9.Cu" signal "VCC1")
		(22 "In10.Cu" signal "GND4")
		(24 "In11.Cu" signal "IN4")
		(26 "In12.Cu" signal "GND5")
		(28 "In13.Cu" signal "IN5")
		(30 "In14.Cu" signal "GND6")
		(32 "In15.Cu" signal "IN6")
		(34 "In16.Cu" signal "GND7")
		(2 "B.Cu" signal "BOTTOM")
		(9 "F.Adhes" user "F.Adhesive")
		(11 "B.Adhes" user "B.Adhesive")
		(13 "F.Paste" user "Package Geometry/Pastemask Top")
		(15 "B.Paste" user "Package Geometry/Pastemask Bottom")
		(5 "F.SilkS" user "Ref Des/Silkscreen Top")
		(7 "B.SilkS" user "Ref Des/Silkscreen Bottom")
		(1 "F.Mask" user "Board Geometry/Soldermask Top")
		(3 "B.Mask" user "Board Geometry/Soldermask Bottom")
		(17 "Dwgs.User" user "User.Drawings")
		(19 "Cmts.User" user "User.Comments")
		(21 "Eco1.User" user "User.Eco1")
		(23 "Eco2.User" user "User.Eco2")
		(25 "Edge.Cuts" user "Board Geometry/Outline")
		(27 "Margin" user)
		(31 "F.CrtYd" user "Package Geometry/Place Bound Top")
		(29 "B.CrtYd" user "Package Geometry/Place Bound Bottom")
		(35 "F.Fab" user "Ref Des/Assembly Top")
		(33 "B.Fab" user "Ref Des/Assembly Bottom")
	)
	(footprint ""
		(layer "F.Cu")
		(at 101.833934 -390.60374 180)
		(property "Reference" "R3397"
			(at 0 0 180)
			(layer "F.SilkS")
			(hide yes)
			(effects
				(font
					(size 1.27 1.27)
				)
			)
		)
		(property "Value" ""
			(at 0 0 180)
			(layer "F.Fab")
			(effects
				(font
					(size 1.27 1.27)
				)
			)
		)
		(duplicate_pad_numbers_are_jumpers no)
		(fp_line
			(start 0.7874 0.4064)
			(end -0.7874 0.4064)
			(stroke
				(width 0.1524)
				(type default)
			)
			(layer "F.SilkS")
		)
		(fp_line
			(start 0.7874 -0.4064)
			(end 0.7874 0.4064)
			(stroke
				(width 0.1524)
				(type default)
			)
			(layer "F.SilkS")
		)
		(fp_line
			(start -0.7874 0.4064)
			(end -0.7874 -0.4064)
			(stroke
				(width 0.1524)
				(type default)
			)
			(layer "F.SilkS")
		)
		(fp_line
			(start -0.7874 -0.4064)
			(end 0.7874 -0.4064)
			(stroke
				(width 0.1524)
				(type default)
			)
			(layer "F.SilkS")
		)
		(fp_line
			(start 0.67945 0.3048)
			(end 0.120396 0.3048)
			(stroke
				(width 0.1)
				(type default)
			)
			(layer "F.Fab")
		)
		(fp_line
			(start 0.67945 -0.3048)
			(end 0.67945 0.3048)
			(stroke
				(width 0.1)
				(type default)
			)
			(layer "F.Fab")
		)
		(fp_line
			(start 0.12065 -0.2794)
			(end 0.12065 -0.3048)
			(stroke
				(width 0.1)
				(type default)
			)
			(layer "F.Fab")
		)
		(fp_line
			(start 0.12065 -0.3048)
			(end 0.67945 -0.3048)
			(stroke
				(width 0.1)
				(type default)
			)
			(layer "F.Fab")
		)
		(fp_line
			(start 0.120396 0.3048)
			(end 0.120396 0.2794)
			(stroke
				(width 0.1)
				(type default)
			)
			(layer "F.Fab")
		)
		(fp_line
			(start 0.120396 0.2794)
			(end -0.12065 0.2794)
			(stroke
				(width 0.1)
				(type default)
			)
			(layer "F.Fab")
		)
		(fp_line
			(start -0.12065 0.3048)
			(end -0.67945 0.3048)
			(stroke
				(width 0.1)
				(type default)
			)
			(layer "F.Fab")
		)
		(fp_line
			(start -0.12065 0.2794)
			(end -0.12065 0.3048)
			(stroke
				(width 0.1)
				(type default)
			)
			(layer "F.Fab")
		)
		(fp_line
			(start -0.12065 -0.2794)
			(end 0.12065 -0.2794)
			(stroke
				(width 0.1)
				(type default)
			)
			(layer "F.Fab")
		)
		(fp_line
			(start -0.12065 -0.305054)
			(end -0.12065 -0.2794)
			(stroke
				(width 0.1)
				(type default)
			)
			(layer "F.Fab")
		)
		(fp_line
			(start -0.67945 0.3048)
			(end -0.67945 -0.305054)
			(stroke
				(width 0.1)
				(type default)
			)
			(layer "F.Fab")
		)
		(fp_line
			(start -0.67945 -0.305054)
			(end -0.12065 -0.305054)
			(stroke
				(width 0.1)
				(type default)
			)
			(layer "F.Fab")
		)
		(pad "1" smd circle
			(at -0.40005 0 180)
			(size 0 0)
			(layers "F.Cu" "F.Mask" "F.Paste")
			(net "GPU_NVS_PWR_BRAKE_N_R")
		)
		(pad "2" smd circle
			(at 0.40005 0 180)
			(size 0 0)
			(layers "F.Cu" "F.Mask" "F.Paste")
			(net "GPU_NVS_PWR_BRAKE_N_BUF")
		)
	)
	(footprint ""
		(layer "F.Cu")
		(at 52.423314 -144.267174 180)
		(property "Reference" "PC441"
			(at 0 0 180)
			(layer "F.SilkS")
			(hide yes)
			(effects
				(font
					(size 1.27 1.27)
				)
			)
		)
		(property "Value" ""
			(at 0 0 180)
			(layer "F.Fab")
			(effects
				(font
					(size 1.27 1.27)
				)
			)
		)
		(duplicate_pad_numbers_are_jumpers no)
		(fp_line
			(start 0.7874 0.4064)
			(end -0.7874 0.4064)
			(stroke
				(width 0.1524)
				(type default)
			)
			(layer "F.SilkS")
		)
		(fp_line
			(start 0.7874 -0.4064)
			(end 0.7874 0.4064)
			(stroke
				(width 0.1524)
				(type default)
			)
			(layer "F.SilkS")
		)
		(fp_line
			(start -0.7874 0.4064)
			(end -0.7874 -0.4064)
			(stroke
				(width 0.1524)
				(type default)
			)
			(layer "F.SilkS")
		)
		(fp_line
			(start -0.7874 -0.4064)
			(end 0.7874 -0.4064)
			(stroke
				(width 0.1524)
				(type default)
			)
			(layer "F.SilkS")
		)
		(fp_line
			(start 0.67945 0.3048)
			(end 0.120396 0.3048)
			(stroke
				(width 0.1)
				(type default)
			)
			(layer "F.Fab")
		)
		(fp_line
			(start 0.67945 -0.3048)
			(end 0.67945 0.3048)
			(stroke
				(width 0.1)
				(type default)
			)
			(layer "F.Fab")
		)
		(fp_line
			(start 0.12065 -0.2794)
			(end 0.12065 -0.3048)
			(stroke
				(width 0.1)
				(type default)
			)
			(layer "F.Fab")
		)
		(fp_line
			(start 0.12065 -0.3048)
			(end 0.67945 -0.3048)
			(stroke
				(width 0.1)
				(type default)
			)
			(layer "F.Fab")
		)
		(fp_line
			(start 0.120396 0.3048)
			(end 0.120396 0.2794)
			(stroke
				(width 0.1)
				(type default)
			)
			(layer "F.Fab")
		)
		(fp_line
			(start 0.120396 0.2794)
			(end -0.12065 0.2794)
			(stroke
				(width 0.1)
				(type default)
			)
			(layer "F.Fab")
		)
		(fp_line
			(start -0.12065 0.3048)
			(end -0.67945 0.3048)
			(stroke
				(width 0.1)
				(type default)
			)
			(layer "F.Fab")
		)
		(fp_line
			(start -0.12065 0.2794)
			(end -0.12065 0.3048)
			(stroke
				(width 0.1)
				(type default)
			)
			(layer "F.Fab")
		)
		(fp_line
			(start -0.12065 -0.2794)
			(end 0.12065 -0.2794)
			(stroke
				(width 0.1)
				(type default)
			)
			(layer "F.Fab")
		)
		(fp_line
			(start -0.12065 -0.305054)
			(end -0.12065 -0.2794)
			(stroke
				(width 0.1)
				(type default)
			)
			(layer "F.Fab")
		)
		(fp_line
			(start -0.67945 0.3048)
			(end -0.67945 -0.305054)
			(stroke
				(width 0.1)
				(type default)
			)
			(layer "F.Fab")
		)
		(fp_line
			(start -0.67945 -0.305054)
			(end -0.12065 -0.305054)
			(stroke
				(width 0.1)
				(type default)
			)
			(layer "F.Fab")
		)
		(pad "1" smd circle
			(at -0.40005 0 180)
			(size 0 0)
			(layers "F.Cu" "F.Mask" "F.Paste")
			(net "PVCCINFAON_CPU1_VDD2")
		)
		(pad "2" smd circle
			(at 0.40005 0 180)
			(size 0 0)
			(layers "F.Cu" "F.Mask" "F.Paste")
			(net "GND")
		)
	)
)
